(kicad_pcb
	(version 20241229)
	(generator "pcbnew")
	(generator_version "9.0")
	(general
		(thickness 1.294)
		(legacy_teardrops no)
	)
	(paper "A3")
	(title_block
		(title "Kintex 410T devboard")
		(date "2024-04-03")
		(rev "1.1.2")
		(comment 9 "footprint 170 of 975 (U1), pads 1-62 of 900")
	)
	(layers
		(0 "F.Cu" mixed)
		(4 "In1.Cu" power)
		(6 "In2.Cu" power)
		(8 "In3.Cu" mixed)
		(10 "In4.Cu" power)
		(12 "In5.Cu" mixed)
		(14 "In6.Cu" power)
		(16 "In7.Cu" mixed)
		(18 "In8.Cu" power)
		(2 "B.Cu" mixed)
		(9 "F.Adhes" user "F.Adhesive")
		(11 "B.Adhes" user "B.Adhesive")
		(13 "F.Paste" user)
		(15 "B.Paste" user)
		(5 "F.SilkS" user "F.Silkscreen")
		(7 "B.SilkS" user "B.Silkscreen")
		(1 "F.Mask" user)
		(3 "B.Mask" user)
		(17 "Dwgs.User" user "User.Drawings")
		(19 "Cmts.User" user "User.Comments")
		(21 "Eco1.User" user "User.Eco1")
		(23 "Eco2.User" user "User.Eco2")
		(25 "Edge.Cuts" user)
		(27 "Margin" user)
		(31 "F.CrtYd" user "F.Courtyard")
		(29 "B.CrtYd" user "B.Courtyard")
		(35 "F.Fab" user)
		(33 "B.Fab" user)
	)
	(footprint "antmicro-footprints:BGA-900_31x31mm_Layout30x30_P1x1mm_FFG900"
		(locked yes)
		(layer "F.Cu")
		(at 200 130)
		(property "Reference" "U1"
			(at -15.74 -15.78 0)
			(layer "F.SilkS")
			(effects
				(font
					(size 0.7 0.7)
					(thickness 0.15)
				)
				(justify left bottom)
			)
		)
		(property "Value" "XC7K410T-2FFG900I"
			(at -4.436 17.635 0)
			(layer "F.Fab")
			(effects
				(font
					(size 0.7 0.7)
					(thickness 0.15)
				)
				(justify left bottom)
			)
		)
		(property "Description" "FPGA, Kintex-7, MMCM, PLL, 350 I/O's, 710 MHz, 406720 Cells, 970 mV to 1.03 V, FCBGA-900"
			(at 0 0 0)
			(layer "F.Fab")
			(hide yes)
			(effects
				(font
					(size 1.27 1.27)
					(thickness 0.15)
				)
			)
		)
		(property "Author" "Antmicro"
			(at 0 0 0)
			(layer "F.Fab")
			(hide yes)
			(effects
				(font
					(size 1 1)
					(thickness 0.15)
				)
			)
		)
		(property "License" "Apache-2.0"
			(at 0 0 0)
			(layer "F.Fab")
			(hide yes)
			(effects
				(font
					(size 1 1)
					(thickness 0.15)
				)
			)
		)
		(property "MPN" "XC7K410T-2FFG900I"
			(at 0 0 0)
			(layer "F.Fab")
			(hide yes)
			(effects
				(font
					(size 1 1)
					(thickness 0.15)
				)
			)
		)
		(property "Manufacturer" "AMD-Xilinx"
			(at 0 0 0)
			(layer "F.Fab")
			(hide yes)
			(effects
				(font
					(size 1 1)
					(thickness 0.15)
				)
			)
		)
		(sheetname "FPGA supply")
		(sheetfile "fpga-supply.kicad_sch")
		(attr smd)
		(pad "A1" smd circle
			(at -14.5 -14.5)
			(size 0.5 0.5)
			(property pad_prop_bga)
			(layers "F.Cu" "F.Mask" "F.Paste")
			(net 1 "GND")
			(pinfunction "GND")
			(pintype "bidirectional")
			(solder_mask_margin 0.02)
		)
		(pad "A2" smd circle
			(at -13.5 -14.5)
			(size 0.5 0.5)
			(property pad_prop_bga)
			(layers "F.Cu" "F.Mask" "F.Paste")
			(net 1 "GND")
			(pinfunction "GND")
			(pintype "passive")
			(solder_mask_margin 0.02)
		)
		(pad "A3" smd circle
			(at -12.5 -14.5)
			(size 0.5 0.5)
			(property pad_prop_bga)
			(layers "F.Cu" "F.Mask" "F.Paste")
			(net 573 "unconnected-(U1G-MGTXTXN3_118-PadA3)")
			(pinfunction "MGTXTXN3_118")
			(pintype "bidirectional+no_connect")
			(die_length 14.432)
			(solder_mask_margin 0.02)
		)
		(pad "A4" smd circle
			(at -11.5 -14.5)
			(size 0.5 0.5)
			(property pad_prop_bga)
			(layers "F.Cu" "F.Mask" "F.Paste")
			(net 574 "unconnected-(U1G-MGTXTXP3_118-PadA4)")
			(pinfunction "MGTXTXP3_118")
			(pintype "bidirectional+no_connect")
			(die_length 14.414)
			(solder_mask_margin 0.02)
		)
		(pad "A5" smd circle
			(at -10.5 -14.5)
			(size 0.5 0.5)
			(property pad_prop_bga)
			(layers "F.Cu" "F.Mask" "F.Paste")
			(net 1 "GND")
			(pinfunction "GND")
			(pintype "passive")
			(solder_mask_margin 0.02)
		)
		(pad "A6" smd circle
			(at -9.5 -14.5)
			(size 0.5 0.5)
			(property pad_prop_bga)
			(layers "F.Cu" "F.Mask" "F.Paste")
			(net 1 "GND")
			(pinfunction "GND")
			(pintype "passive")
			(solder_mask_margin 0.02)
		)
		(pad "A7" smd circle
			(at -8.5 -14.5)
			(size 0.5 0.5)
			(property pad_prop_bga)
			(layers "F.Cu" "F.Mask" "F.Paste")
			(net 575 "unconnected-(U1G-MGTXRXN3_118-PadA7)")
			(pinfunction "MGTXRXN3_118")
			(pintype "bidirectional+no_connect")
			(die_length 11.951)
			(solder_mask_margin 0.02)
		)
		(pad "A8" smd circle
			(at -7.5 -14.5)
			(size 0.5 0.5)
			(property pad_prop_bga)
			(layers "F.Cu" "F.Mask" "F.Paste")
			(net 576 "unconnected-(U1G-MGTXRXP3_118-PadA8)")
			(pinfunction "MGTXRXP3_118")
			(pintype "bidirectional+no_connect")
			(die_length 11.93)
			(solder_mask_margin 0.02)
		)
		(pad "A9" smd circle
			(at -6.5 -14.5)
			(size 0.5 0.5)
			(property pad_prop_bga)
			(layers "F.Cu" "F.Mask" "F.Paste")
			(net 1 "GND")
			(pinfunction "GND")
			(pintype "passive")
			(solder_mask_margin 0.02)
		)
		(pad "A10" smd circle
			(at -5.5 -14.5)
			(size 0.5 0.5)
			(property pad_prop_bga)
			(layers "F.Cu" "F.Mask" "F.Paste")
			(net 257 "/FPGA Config/INIT_B")
			(pinfunction "INIT_B_0")
			(pintype "bidirectional")
			(die_length 30.087)
			(solder_mask_margin 0.02)
		)
		(pad "A11" smd circle
			(at -4.5 -14.5)
			(size 0.5 0.5)
			(property pad_prop_bga)
			(layers "F.Cu" "F.Mask" "F.Paste")
			(net 428 "/FMC+ HSPC/FMC.IO17_P")
			(pinfunction "IO_L17P_T2_18")
			(pintype "bidirectional")
			(die_length 26.57)
			(solder_mask_margin 0.02)
		)
		(pad "A12" smd circle
			(at -3.5 -14.5)
			(size 0.5 0.5)
			(property pad_prop_bga)
			(layers "F.Cu" "F.Mask" "F.Paste")
			(net 426 "/FMC+ HSPC/FMC.IO17_N")
			(pinfunction "IO_L17N_T2_18")
			(pintype "bidirectional")
			(die_length 25.299)
			(solder_mask_margin 0.02)
		)
		(pad "A13" smd circle
			(at -2.5 -14.5)
			(size 0.5 0.5)
			(property pad_prop_bga)
			(layers "F.Cu" "F.Mask" "F.Paste")
			(net 634 "/FMC+ HSPC/FMC.IO22_N")
			(pinfunction "IO_L22N_T3_18")
			(pintype "bidirectional")
			(die_length 25.219)
			(solder_mask_margin 0.02)
		)
		(pad "A14" smd circle
			(at -1.5 -14.5)
			(size 0.5 0.5)
			(property pad_prop_bga)
			(layers "F.Cu" "F.Mask" "F.Paste")
			(net 1 "GND")
			(pinfunction "GND")
			(pintype "passive")
			(solder_mask_margin 0.02)
		)
		(pad "A15" smd circle
			(at -0.5 -14.5)
			(size 0.5 0.5)
			(property pad_prop_bga)
			(layers "F.Cu" "F.Mask" "F.Paste")
			(net 349 "/FMC+ HSPC/FMC.IO24_N")
			(pinfunction "IO_L24N_T3_18")
			(pintype "bidirectional")
			(die_length 24.216)
			(solder_mask_margin 0.02)
		)
		(pad "A16" smd circle
			(at 0.5 -14.5)
			(size 0.5 0.5)
			(property pad_prop_bga)
			(layers "F.Cu" "F.Mask" "F.Paste")
			(net 578 "/FPGA Bank 12 & 13/USB_HOST.CLK")
			(pinfunction "IO_L20P_T3_17")
			(pintype "bidirectional")
			(die_length 26.083)
			(solder_mask_margin 0.02)
		)
		(pad "A17" smd circle
			(at 1.5 -14.5)
			(size 0.5 0.5)
			(property pad_prop_bga)
			(layers "F.Cu" "F.Mask" "F.Paste")
			(net 579 "/FPGA Bank 12 & 13/USB_HOST.MISO")
			(pinfunction "IO_L20N_T3_17")
			(pintype "bidirectional")
			(die_length 25.395)
			(solder_mask_margin 0.02)
		)
		(pad "A18" smd circle
			(at 2.5 -14.5)
			(size 0.5 0.5)
			(property pad_prop_bga)
			(layers "F.Cu" "F.Mask" "F.Paste")
			(net 580 "/FPGA Bank 12 & 13/USB_HOST.GPX")
			(pinfunction "IO_L22N_T3_17")
			(pintype "bidirectional")
			(die_length 25.265)
			(solder_mask_margin 0.02)
		)
		(pad "A19" smd circle
			(at 3.5 -14.5)
			(size 0.5 0.5)
			(property pad_prop_bga)
			(layers "F.Cu" "F.Mask" "F.Paste")
			(net 24 "+3V3")
			(pinfunction "VCCO_17")
			(pintype "bidirectional")
			(solder_mask_margin 0.02)
		)
		(pad "A20" smd circle
			(at 4.5 -14.5)
			(size 0.5 0.5)
			(property pad_prop_bga)
			(layers "F.Cu" "F.Mask" "F.Paste")
			(net 581 "unconnected-(U1C-IO_L21P_T3_DQS_17-PadA20)")
			(pinfunction "IO_L21P_T3_DQS_17")
			(pintype "bidirectional+no_connect")
			(die_length 23.453)
			(solder_mask_margin 0.02)
		)
		(pad "A21" smd circle
			(at 5.5 -14.5)
			(size 0.5 0.5)
			(property pad_prop_bga)
			(layers "F.Cu" "F.Mask" "F.Paste")
			(net 582 "unconnected-(U1C-IO_L21N_T3_DQS_17-PadA21)")
			(pinfunction "IO_L21N_T3_DQS_17")
			(pintype "bidirectional+no_connect")
			(die_length 23.28)
			(solder_mask_margin 0.02)
		)
		(pad "A22" smd circle
			(at 6.5 -14.5)
			(size 0.5 0.5)
			(property pad_prop_bga)
			(layers "F.Cu" "F.Mask" "F.Paste")
			(net 565 "/FPGA Bank 16 & 17/HDMI.CLK_N")
			(pinfunction "IO_L23N_T3_17")
			(pintype "bidirectional")
			(die_length 21.922)
			(solder_mask_margin 0.02)
		)
		(pad "A23" smd circle
			(at 7.5 -14.5)
			(size 0.5 0.5)
			(property pad_prop_bga)
			(layers "F.Cu" "F.Mask" "F.Paste")
			(net 1271 "/USER_IO.B8")
			(pinfunction "IO_L1N_T0_16")
			(pintype "bidirectional")
			(die_length 22.02)
			(solder_mask_margin 0.02)
		)
		(pad "A24" smd circle
			(at 8.5 -14.5)
			(size 0.5 0.5)
			(property pad_prop_bga)
			(layers "F.Cu" "F.Mask" "F.Paste")
			(net 1 "GND")
			(pinfunction "GND")
			(pintype "passive")
			(solder_mask_margin 0.02)
		)
		(pad "A25" smd circle
			(at 9.5 -14.5)
			(size 0.5 0.5)
			(property pad_prop_bga)
			(layers "F.Cu" "F.Mask" "F.Paste")
			(net 1284 "/USER_IO.B24")
			(pinfunction "IO_L10P_T1_16")
			(pintype "bidirectional")
			(die_length 23.09)
			(solder_mask_margin 0.02)
		)
		(pad "A26" smd circle
			(at 10.5 -14.5)
			(size 0.5 0.5)
			(property pad_prop_bga)
			(layers "F.Cu" "F.Mask" "F.Paste")
			(net 1274 "/USER_IO.B11")
			(pinfunction "IO_L10N_T1_16")
			(pintype "bidirectional")
			(die_length 24.986)
			(solder_mask_margin 0.02)
		)
		(pad "A27" smd circle
			(at 11.5 -14.5)
			(size 0.5 0.5)
			(property pad_prop_bga)
			(layers "F.Cu" "F.Mask" "F.Paste")
			(net 1273 "/USER_IO.B10")
			(pinfunction "IO_L7N_T1_16")
			(pintype "bidirectional")
			(die_length 22.513)
			(solder_mask_margin 0.02)
		)
		(pad "A28" smd circle
			(at 12.5 -14.5)
			(size 0.5 0.5)
			(property pad_prop_bga)
			(layers "F.Cu" "F.Mask" "F.Paste")
			(net 1272 "/USER_IO.B9")
			(pinfunction "IO_L9N_T1_DQS_16")
			(pintype "bidirectional")
			(die_length 23.234)
			(solder_mask_margin 0.02)
		)
		(pad "A29" smd circle
			(at 13.5 -14.5)
			(size 0.5 0.5)
			(property pad_prop_bga)
			(layers "F.Cu" "F.Mask" "F.Paste")
			(net 3 "VCC_USR_B")
			(pinfunction "VCCO_16")
			(pintype "bidirectional")
			(solder_mask_margin 0.02)
		)
		(pad "A30" smd circle
			(at 14.5 -14.5)
			(size 0.5 0.5)
			(property pad_prop_bga)
			(layers "F.Cu" "F.Mask" "F.Paste")
			(net 1267 "/USER_IO.B3")
			(pinfunction "IO_L17N_T2_16")
			(pintype "bidirectional")
			(die_length 24.871)
			(solder_mask_margin 0.02)
		)
		(pad "AA1" smd circle
			(at -14.5 5.5)
			(size 0.5 0.5)
			(property pad_prop_bga)
			(layers "F.Cu" "F.Mask" "F.Paste")
			(net 1 "GND")
			(pinfunction "GND")
			(pintype "passive")
			(solder_mask_margin 0.02)
		)
		(pad "AA2" smd circle
			(at -13.5 5.5)
			(size 0.5 0.5)
			(property pad_prop_bga)
			(layers "F.Cu" "F.Mask" "F.Paste")
			(net 1 "GND")
			(pinfunction "GND")
			(pintype "passive")
			(solder_mask_margin 0.02)
		)
		(pad "AA3" smd circle
			(at -12.5 5.5)
			(size 0.5 0.5)
			(property pad_prop_bga)
			(layers "F.Cu" "F.Mask" "F.Paste")
			(net 483 "/FMC+ HSPC/GTX115.RX0_N")
			(pinfunction "MGTXRXN0_115")
			(pintype "bidirectional")
			(die_length 17.779)
			(solder_mask_margin 0.02)
		)
		(pad "AA4" smd circle
			(at -11.5 5.5)
			(size 0.5 0.5)
			(property pad_prop_bga)
			(layers "F.Cu" "F.Mask" "F.Paste")
			(net 486 "/FMC+ HSPC/GTX115.RX0_P")
			(pinfunction "MGTXRXP0_115")
			(pintype "bidirectional")
			(die_length 17.802)
			(solder_mask_margin 0.02)
		)
		(pad "AA5" smd circle
			(at -10.5 5.5)
			(size 0.5 0.5)
			(property pad_prop_bga)
			(layers "F.Cu" "F.Mask" "F.Paste")
			(net 1 "GND")
			(pinfunction "GND")
			(pintype "passive")
			(solder_mask_margin 0.02)
		)
		(pad "AA6" smd circle
			(at -9.5 5.5)
			(size 0.5 0.5)
			(property pad_prop_bga)
			(layers "F.Cu" "F.Mask" "F.Paste")
			(net 1 "GND")
			(pinfunction "GND")
			(pintype "passive")
			(solder_mask_margin 0.02)
		)
		(pad "AA7" smd circle
			(at -8.5 5.5)
			(size 0.5 0.5)
			(property pad_prop_bga)
			(layers "F.Cu" "F.Mask" "F.Paste")
			(net 1 "GND")
			(pinfunction "GND")
			(pintype "passive")
			(solder_mask_margin 0.02)
		)
		(pad "AA8" smd circle
			(at -7.5 5.5)
			(size 0.5 0.5)
			(property pad_prop_bga)
			(layers "F.Cu" "F.Mask" "F.Paste")
			(net 1309 "/USER_IO.DIP_SW2")
			(pinfunction "IO_L2P_T0_33")
			(pintype "bidirectional")
			(die_length 14.905)
			(solder_mask_margin 0.02)
		)
		(pad "AA9" smd circle
			(at -6.5 5.5)
			(size 0.5 0.5)
			(property pad_prop_bga)
			(layers "F.Cu" "F.Mask" "F.Paste")
			(net 26 "+1V8")
			(pinfunction "VCCO_33")
			(pintype "bidirectional")
			(solder_mask_margin 0.02)
		)
		(pad "AA10" smd circle
			(at -5.5 5.5 90)
			(size 0.5 0.5)
			(property pad_prop_bga)
			(layers "F.Cu" "F.Mask" "F.Paste")
			(net 13 "/USER_IO.BUTTON1")
			(pinfunction "IO_L5N_T0_33")
			(pintype "bidirectional")
			(die_length 8.194)
			(solder_mask_margin 0.02)
		)
		(pad "AA11" smd circle
			(at -4.5 5.5)
			(size 0.5 0.5)
			(property pad_prop_bga)
			(layers "F.Cu" "F.Mask" "F.Paste")
			(net 1228 "/USER_IO.BUTTON0")
			(pinfunction "IO_L5P_T0_33")
			(pintype "bidirectional")
			(die_length 8.33)
			(solder_mask_margin 0.02)
		)
		(pad "AA12" smd circle
			(at -3.5 5.5)
			(size 0.5 0.5)
			(property pad_prop_bga)
			(layers "F.Cu" "F.Mask" "F.Paste")
			(net 1318 "/USER_IO.DIP_SW7")
			(pinfunction "IO_L1P_T0_33")
			(pintype "bidirectional")
			(die_length 8.782)
			(solder_mask_margin 0.02)
		)
		(pad "AA13" smd circle
			(at -2.5 5.5)
			(size 0.5 0.5)
			(property pad_prop_bga)
			(layers "F.Cu" "F.Mask" "F.Paste")
			(net 1324 "/USER_IO.DIP_SW4")
			(pinfunction "IO_L6P_T0_33")
			(pintype "bidirectional")
			(die_length 10.996)
			(solder_mask_margin 0.02)
		)
		(pad "AA14" smd circle
			(at -1.5 5.5)
			(size 0.5 0.5)
			(property pad_prop_bga)
			(layers "F.Cu" "F.Mask" "F.Paste")
			(net 1 "GND")
			(pinfunction "GND")
			(pintype "passive")
			(solder_mask_margin 0.02)
		)
		(pad "AA15" smd circle
			(at -0.5 5.5)
			(size 0.5 0.5)
			(property pad_prop_bga)
			(layers "F.Cu" "F.Mask" "F.Paste")
			(net 584 "/FPGA Bank 12 & 13/USB_USER.VP")
			(pinfunction "IO_L20P_T3_32")
			(pintype "bidirectional")
			(die_length 12.195)
			(solder_mask_margin 0.02)
		)
		(pad "AA16" smd circle
			(at 0.5 5.5)
			(size 0.5 0.5)
			(property pad_prop_bga)
			(layers "F.Cu" "F.Mask" "F.Paste")
			(net 511 "/FPGA Bank 18 & 32/ETH_RMII.TXEN")
			(pinfunction "IO_L23N_T3_32")
			(pintype "bidirectional")
			(die_length 14.54)
			(solder_mask_margin 0.02)
		)
		(pad "AA17" smd circle
			(at 1.5 5.5)
			(size 0.5 0.5)
			(property pad_prop_bga)
			(layers "F.Cu" "F.Mask" "F.Paste")
			(net 585 "unconnected-(U1D-IO_L23P_T3_32-PadAA17)")
			(pinfunction "IO_L23P_T3_32")
			(pintype "bidirectional+no_connect")
			(die_length 16.445)
			(solder_mask_margin 0.02)
		)
		(pad "AA18" smd circle
			(at 2.5 5.5)
			(size 0.5 0.5)
			(property pad_prop_bga)
			(layers "F.Cu" "F.Mask" "F.Paste")
			(net 502 "/FPGA Bank 18 & 32/ETH_RMII.MDIO")
			(pinfunction "IO_L16P_T2_32")
			(pintype "bidirectional")
			(die_length 23.589)
			(solder_mask_margin 0.02)
		)
		(pad "AA19" smd circle
			(at 3.5 5.5)
			(size 0.5 0.5)
			(property pad_prop_bga)
			(layers "F.Cu" "F.Mask" "F.Paste")
			(net 26 "+1V8")
			(pinfunction "VCCO_32")
			(pintype "bidirectional")
			(solder_mask_margin 0.02)
		)
		(pad "AA20" smd circle
			(at 4.5 5.5)
			(size 0.5 0.5)
			(property pad_prop_bga)
			(layers "F.Cu" "F.Mask" "F.Paste")
			(net 1363 "/SUP_MCU.A17")
			(pinfunction "IO_L6P_T0_12")
			(pintype "bidirectional")
			(die_length 6.201)
			(solder_mask_margin 0.02)
		)
		(pad "AA21" smd circle
			(at 5.5 5.5)
			(size 0.5 0.5)
			(property pad_prop_bga)
			(layers "F.Cu" "F.Mask" "F.Paste")
			(net 1372 "/SUP_MCU.D0")
			(pinfunction "IO_L2N_T0_12")
			(pintype "bidirectional")
			(die_length 9.235)
			(solder_mask_margin 0.02)
		)
		(pad "AA22" smd circle
			(at 6.5 5.5)
			(size 0.5 0.5)
			(property pad_prop_bga)
			(layers "F.Cu" "F.Mask" "F.Paste")
			(net 1382 "/SUP_MCU.D1")
			(pinfunction "IO_L4P_T0_12")
			(pintype "bidirectional")
			(die_length 8.789)
			(solder_mask_margin 0.02)
		)
		(pad "AA23" smd circle
			(at 7.5 5.5)
			(size 0.5 0.5)
			(property pad_prop_bga)
			(layers "F.Cu" "F.Mask" "F.Paste")
			(net 1381 "/SUP_MCU.D4")
			(pinfunction "IO_L4N_T0_12")
			(pintype "bidirectional")
			(die_length 8.88)
			(solder_mask_margin 0.02)
		)
		(pad "AA24" smd circle
			(at 8.5 5.5)
			(size 0.5 0.5)
			(property pad_prop_bga)
			(layers "F.Cu" "F.Mask" "F.Paste")
			(net 1 "GND")
			(pinfunction "GND")
			(pintype "passive")
			(solder_mask_margin 0.02)
		)
		(pad "AA25" smd circle
			(at 9.5 5.5)
			(size 0.5 0.5)
			(property pad_prop_bga)
			(layers "F.Cu" "F.Mask" "F.Paste")
			(net 433 "/FPGA Bank 12 & 13/PMOD_A.IO7")
			(pinfunction "IO_L6P_T0_13")
			(pintype "bidirectional")
			(die_length 12.199)
			(solder_mask_margin 0.02)
		)
		(pad "AA26" smd circle
			(at 10.5 5.5)
			(size 0.5 0.5)
			(property pad_prop_bga)
			(layers "F.Cu" "F.Mask" "F.Paste")
			(net 1302 "/USER_IO.LED_GREEN3")
			(pinfunction "IO_L1N_T0_13")
			(pintype "bidirectional")
			(die_length 12.222)
			(solder_mask_margin 0.02)
		)
		(pad "AA27" smd circle
			(at 11.5 5.5)
			(size 0.5 0.5)
			(property pad_prop_bga)
			(layers "F.Cu" "F.Mask" "F.Paste")
			(net 451 "/FPGA Bank 12 & 13/PMOD_B.IO8")
			(pinfunction "IO_L5P_T0_13")
			(pintype "bidirectional")
			(die_length 12.889)
			(solder_mask_margin 0.02)
		)
		(pad "AA28" smd circle
			(at 12.5 5.5)
			(size 0.5 0.5)
			(property pad_prop_bga)
			(layers "F.Cu" "F.Mask" "F.Paste")
			(net 1301 "/USER_IO.LED_GREEN2")
			(pinfunction "IO_L3N_T0_DQS_13")
			(pintype "bidirectional")
			(die_length 14.752)
			(solder_mask_margin 0.02)
		)
		(pad "AA29" smd circle
			(at 13.5 5.5)
			(size 0.5 0.5)
			(property pad_prop_bga)
			(layers "F.Cu" "F.Mask" "F.Paste")
			(net 24 "+3V3")
			(pinfunction "VCCO_13")
			(pintype "bidirectional")
			(solder_mask_margin 0.02)
		)
		(pad "AA30" smd circle
			(at 14.5 5.5)
			(size 0.5 0.5)
			(property pad_prop_bga)
			(layers "F.Cu" "F.Mask" "F.Paste")
			(net 1303 "/USER_IO.LED_GREEN4")
			(pinfunction "IO_L8N_T1_13")
			(pintype "bidirectional")
			(die_length 18.273)
			(solder_mask_margin 0.02)
		)
		(pad "AB1" smd circle
			(at -14.5 6.5)
			(size 0.5 0.5)
			(property pad_prop_bga)
			(layers "F.Cu" "F.Mask" "F.Paste")
			(net 298 "/FPGA Config/MODE2")
			(pinfunction "M2_0")
			(pintype "bidirectional")
			(die_length 28.796)
			(solder_mask_margin 0.02)
		)
		(pad "AB2" smd circle
			(at -13.5 6.5)
			(size 0.5 0.5)
			(property pad_prop_bga)
			(layers "F.Cu" "F.Mask" "F.Paste")
			(net 299 "/FPGA Config/MODE1")
			(pinfunction "M1_0")
			(pintype "bidirectional")
			(die_length 27.299)
			(solder_mask_margin 0.02)
		)
	)
)
